(kicad_pcb
	(version 20241229)
	(generator "pcbnew")
	(generator_version "9.0")
	(general
		(thickness 1.63)
		(legacy_teardrops no)
	)
	(paper "A4")
	(title_block
		(title "CM4 Baseboard")
		(date "2026-01-05")
		(rev "1.1.1")
		(company "Antmicro Ltd")
		(comment 1 "www.antmicro.com")
		(comment 9 "footprints 349-353 of 506")
	)
	(layers
		(0 "F.Cu" signal)
		(4 "In1.Cu" power)
		(6 "In2.Cu" power)
		(8 "In3.Cu" signal)
		(10 "In4.Cu" signal)
		(2 "B.Cu" signal)
		(9 "F.Adhes" user "F.Adhesive")
		(11 "B.Adhes" user "B.Adhesive")
		(13 "F.Paste" user)
		(15 "B.Paste" user)
		(5 "F.SilkS" user "F.Silkscreen")
		(7 "B.SilkS" user "B.Silkscreen")
		(1 "F.Mask" user)
		(3 "B.Mask" user)
		(17 "Dwgs.User" user "User.Drawings")
		(19 "Cmts.User" user "User.Comments")
		(21 "Eco1.User" user "User.Eco1")
		(23 "Eco2.User" user "User.Eco2")
		(25 "Edge.Cuts" user)
		(27 "Margin" user)
		(31 "F.CrtYd" user "F.Courtyard")
		(29 "B.CrtYd" user "B.Courtyard")
		(35 "F.Fab" user)
		(33 "B.Fab" user)
	)
	(footprint "antmicro-footprints:R_0603_1608Metric"
		(layer "B.Cu")
		(at 40.1 162.7 90)
		(descr "Resistor SMD 0603")
		(tags "resistor SMD 0603")
		(property "Reference" "R328"
			(at -1.4 -0.7 90)
			(layer "B.SilkS")
			(effects
				(font
					(size 0.7 0.7)
					(thickness 0.15)
				)
				(justify right bottom mirror)
			)
		)
		(property "Value" "R_0R_22.4A_0603"
			(at 0 -1.6 90)
			(layer "B.Fab")
			(effects
				(font
					(size 0.7 0.7)
					(thickness 0.15)
				)
				(justify right bottom mirror)
			)
		)
		(property "Datasheet" "https://fscdn.rohm.com/en/products/databook/datasheet/passive/resistor/chip_resistor/pmr-jpw-e.pdf"
			(at 0 0 90)
			(layer "B.Fab")
			(hide yes)
			(effects
				(font
					(size 1.27 1.27)
					(thickness 0.15)
				)
			)
		)
		(property "Manufacturer" "ROHM Semiconductor"
			(at 0 0 90)
			(unlocked yes)
			(layer "B.Fab")
			(hide yes)
			(effects
				(font
					(size 1 1)
					(thickness 0.15)
				)
				(justify mirror)
			)
		)
		(property "MPN" "PMR03EZPJ000"
			(at 0 0 90)
			(unlocked yes)
			(layer "B.Fab")
			(hide yes)
			(effects
				(font
					(size 1 1)
					(thickness 0.15)
				)
				(justify mirror)
			)
		)
		(property "Val" "0R"
			(at 0 0 90)
			(unlocked yes)
			(layer "B.Fab")
			(hide yes)
			(effects
				(font
					(size 1 1)
					(thickness 0.15)
				)
				(justify mirror)
			)
		)
		(property "Author" "Antmicro"
			(at 0 0 90)
			(unlocked yes)
			(layer "B.Fab")
			(hide yes)
			(effects
				(font
					(size 1 1)
					(thickness 0.15)
				)
				(justify mirror)
			)
		)
		(property "License" "Apache-2.0"
			(at 0 0 90)
			(unlocked yes)
			(layer "B.Fab")
			(hide yes)
			(effects
				(font
					(size 1 1)
					(thickness 0.15)
				)
				(justify mirror)
			)
		)
		(property "Max. Curr." "22.4A"
			(at 0 0 90)
			(unlocked yes)
			(layer "B.Fab")
			(hide yes)
			(effects
				(font
					(size 1 1)
					(thickness 0.15)
				)
				(justify mirror)
			)
		)
		(property "Tolerance" "template_tolerance"
			(at 0 0 90)
			(unlocked yes)
			(layer "B.Fab")
			(hide yes)
			(effects
				(font
					(size 1 1)
					(thickness 0.15)
				)
				(justify mirror)
			)
		)
		(sheetname "/Supply/")
		(sheetfile "supply.kicad_sch")
		(attr smd exclude_from_pos_files exclude_from_bom dnp)
		(fp_line
			(start -0.15 -0.4)
			(end 0.15 -0.4)
			(stroke
				(width 0.15)
				(type solid)
			)
			(layer "B.SilkS")
		)
		(fp_line
			(start -0.15 0.4)
			(end 0.15 0.4)
			(stroke
				(width 0.15)
				(type solid)
			)
			(layer "B.SilkS")
		)
		(fp_rect
			(start -1.25 0.65)
			(end 1.25 -0.65)
			(stroke
				(width 0.05)
				(type solid)
			)
			(fill no)
			(layer "B.CrtYd")
		)
		(fp_rect
			(start -0.8 0.4)
			(end 0.8 -0.4)
			(stroke
				(width 0.15)
				(type solid)
			)
			(fill no)
			(layer "B.Fab")
		)
		(fp_text user "${REFERENCE}"
			(at -1.25 -3.898 270)
			(layer "B.Fab")
			(effects
				(font
					(size 0.7 0.7)
					(thickness 0.15)
				)
				(justify left bottom mirror)
			)
		)
		(fp_text user "License: Apache-2.0"
			(at -1.25 -5.9 270)
			(layer "B.Fab")
			(effects
				(font
					(size 0.7 0.7)
					(thickness 0.15)
				)
				(justify left bottom mirror)
			)
		)
		(fp_text user "Author: Antmicro"
			(at -1.25 -4.9 270)
			(layer "B.Fab")
			(effects
				(font
					(size 0.7 0.7)
					(thickness 0.15)
				)
				(justify left bottom mirror)
			)
		)
		(pad "1" smd roundrect
			(at -0.7 0 90)
			(size 0.8 1)
			(layers "B.Cu" "B.Mask" "B.Paste")
			(roundrect_rratio 0.2)
			(net 472 "Net-(D301-C)")
			(pintype "passive")
		)
		(pad "2" smd roundrect
			(at 0.7 0 90)
			(size 0.8 1)
			(layers "B.Cu" "B.Mask" "B.Paste")
			(roundrect_rratio 0.2)
			(net 21 "/Supply/VCC_IN")
			(pintype "passive")
		)
	)
	(footprint "antmicro-footprints:C_0402_1005Metric"
		(layer "B.Cu")
		(at 134.567962 146.4915 -90)
		(descr "Capacitor SMD 0402")
		(tags "capacitor SMD 0402")
		(property "Reference" "C603"
			(at -3.765 -0.16 90)
			(layer "B.SilkS")
			(effects
				(font
					(size 0.7 0.7)
					(thickness 0.15)
				)
				(justify left bottom mirror)
			)
		)
		(property "Value" "C_1u_0402"
			(at -1.022927 -2.155213 90)
			(layer "B.Fab")
			(effects
				(font
					(size 0.7 0.7)
					(thickness 0.15)
				)
				(justify left bottom mirror)
			)
		)
		(property "Datasheet" "https://product.tdk.com/en/search/capacitor/ceramic/mlcc/info?part_no=C1005X6S1A105K050BC"
			(at 0 0 270)
			(layer "B.Fab")
			(hide yes)
			(effects
				(font
					(size 1.27 1.27)
					(thickness 0.15)
				)
			)
		)
		(property "Manufacturer" "TDK"
			(at 0 0 270)
			(unlocked yes)
			(layer "B.Fab")
			(hide yes)
			(effects
				(font
					(size 1 1)
					(thickness 0.15)
				)
				(justify mirror)
			)
		)
		(property "MPN" "C1005X6S1A105K050BC"
			(at 0 0 270)
			(unlocked yes)
			(layer "B.Fab")
			(hide yes)
			(effects
				(font
					(size 1 1)
					(thickness 0.15)
				)
				(justify mirror)
			)
		)
		(property "Val" "1u"
			(at 0 0 270)
			(unlocked yes)
			(layer "B.Fab")
			(hide yes)
			(effects
				(font
					(size 1 1)
					(thickness 0.15)
				)
				(justify mirror)
			)
		)
		(property "License" "Apache-2.0"
			(at 0 0 270)
			(unlocked yes)
			(layer "B.Fab")
			(hide yes)
			(effects
				(font
					(size 1 1)
					(thickness 0.15)
				)
				(justify mirror)
			)
		)
		(property "Author" "Antmicro"
			(at 0 0 270)
			(unlocked yes)
			(layer "B.Fab")
			(hide yes)
			(effects
				(font
					(size 1 1)
					(thickness 0.15)
				)
				(justify mirror)
			)
		)
		(property "Voltage" ""
			(at 0 0 270)
			(unlocked yes)
			(layer "B.Fab")
			(hide yes)
			(effects
				(font
					(size 1 1)
					(thickness 0.15)
				)
				(justify mirror)
			)
		)
		(property "Dielectric" ""
			(at 0 0 270)
			(unlocked yes)
			(layer "B.Fab")
			(hide yes)
			(effects
				(font
					(size 1 1)
					(thickness 0.15)
				)
				(justify mirror)
			)
		)
		(sheetname "/CSI/")
		(sheetfile "csi.kicad_sch")
		(attr smd)
		(fp_rect
			(start -0.925 0.47)
			(end 0.925 -0.47)
			(stroke
				(width 0.05)
				(type default)
			)
			(fill no)
			(layer "B.CrtYd")
		)
		(fp_line
			(start -0.494 0.25)
			(end 0.504 0.25)
			(stroke
				(width 0.15)
				(type solid)
			)
			(layer "B.Fab")
		)
		(fp_line
			(start 0.504 0.25)
			(end 0.504 -0.248)
			(stroke
				(width 0.15)
				(type solid)
			)
			(layer "B.Fab")
		)
		(fp_line
			(start -0.494 -0.248)
			(end -0.494 0.25)
			(stroke
				(width 0.15)
				(type solid)
			)
			(layer "B.Fab")
		)
		(fp_line
			(start 0.504 -0.248)
			(end -0.494 -0.248)
			(stroke
				(width 0.15)
				(type solid)
			)
			(layer "B.Fab")
		)
		(fp_text user "License: Apache-2.0"
			(at -0.939 -5.799 90)
			(layer "B.Fab")
			(effects
				(font
					(size 0.7 0.7)
					(thickness 0.15)
				)
				(justify left bottom mirror)
			)
		)
		(fp_text user "${REFERENCE}"
			(at -0.939 -4.599 90)
			(layer "B.Fab")
			(effects
				(font
					(size 0.7 0.7)
					(thickness 0.15)
				)
				(justify left bottom mirror)
			)
		)
		(fp_text user "Author: Antmicro"
			(at -0.939 -3.399 90)
			(layer "B.Fab")
			(effects
				(font
					(size 0.7 0.7)
					(thickness 0.15)
				)
				(justify left bottom mirror)
			)
		)
		(pad "1" smd roundrect
			(at -0.48 0 270)
			(size 0.59 0.64)
			(layers "B.Cu" "B.Mask" "B.Paste")
			(roundrect_rratio 0.25)
			(net 3 "GND")
			(pintype "passive")
		)
		(pad "2" smd roundrect
			(at 0.48 0 270)
			(size 0.59 0.64)
			(layers "B.Cu" "B.Mask" "B.Paste")
			(roundrect_rratio 0.25)
			(net 19 "/CSI/CSI_3V3")
			(pintype "passive")
		)
	)
	(footprint "antmicro-footprints:R_0402_1005Metric"
		(layer "B.Cu")
		(at 86.842962 122.1665 180)
		(descr "Resistor SMD 0402")
		(tags "resistor SMD 0402")
		(property "Reference" "R909"
			(at 0.985 0.4 0)
			(layer "B.SilkS")
			(effects
				(font
					(size 0.7 0.7)
					(thickness 0.15)
				)
				(justify left bottom mirror)
			)
		)
		(property "Value" "R_10k_0402"
			(at -1.011843 -1.772047 0)
			(layer "B.Fab")
			(effects
				(font
					(size 0.7 0.7)
					(thickness 0.15)
				)
				(justify left bottom mirror)
			)
		)
		(property "Datasheet" "https://www.bourns.com/docs/product-datasheets/cr.pdf"
			(at 0 0 180)
			(layer "B.Fab")
			(hide yes)
			(effects
				(font
					(size 1.27 1.27)
					(thickness 0.15)
				)
			)
		)
		(property "Manufacturer" "Bourns"
			(at 0 0 180)
			(unlocked yes)
			(layer "B.Fab")
			(hide yes)
			(effects
				(font
					(size 1 1)
					(thickness 0.15)
				)
				(justify mirror)
			)
		)
		(property "MPN" "CR0402-FX-1002GLF"
			(at 0 0 180)
			(unlocked yes)
			(layer "B.Fab")
			(hide yes)
			(effects
				(font
					(size 1 1)
					(thickness 0.15)
				)
				(justify mirror)
			)
		)
		(property "Val" "10k"
			(at 0 0 180)
			(unlocked yes)
			(layer "B.Fab")
			(hide yes)
			(effects
				(font
					(size 1 1)
					(thickness 0.15)
				)
				(justify mirror)
			)
		)
		(property "License" "Apache-2.0"
			(at 0 0 180)
			(unlocked yes)
			(layer "B.Fab")
			(hide yes)
			(effects
				(font
					(size 1 1)
					(thickness 0.15)
				)
				(justify mirror)
			)
		)
		(property "Author" "Antmicro"
			(at 0 0 180)
			(unlocked yes)
			(layer "B.Fab")
			(hide yes)
			(effects
				(font
					(size 1 1)
					(thickness 0.15)
				)
				(justify mirror)
			)
		)
		(property "Tolerance" "1%"
			(at 0 0 180)
			(unlocked yes)
			(layer "B.Fab")
			(hide yes)
			(effects
				(font
					(size 1 1)
					(thickness 0.15)
				)
				(justify mirror)
			)
		)
		(sheetname "/USB/")
		(sheetfile "usb.kicad_sch")
		(attr smd)
		(fp_rect
			(start -0.925 0.47)
			(end 0.925 -0.47)
			(stroke
				(width 0.05)
				(type default)
			)
			(fill no)
			(layer "B.CrtYd")
		)
		(fp_rect
			(start -0.5 0.25)
			(end 0.5 -0.25)
			(stroke
				(width 0.15)
				(type solid)
			)
			(fill no)
			(layer "B.Fab")
		)
		(fp_text user "${REFERENCE}"
			(at -0.95 -3.168 0)
			(layer "B.Fab")
			(effects
				(font
					(size 0.7 0.7)
					(thickness 0.15)
				)
				(justify left bottom mirror)
			)
		)
		(fp_text user "Author: Antmicro"
			(at -0.95 -4.169 0)
			(layer "B.Fab")
			(effects
				(font
					(size 0.7 0.7)
					(thickness 0.15)
				)
				(justify left bottom mirror)
			)
		)
		(fp_text user "License: Apache-2.0"
			(at -0.95 -5.169 0)
			(layer "B.Fab")
			(effects
				(font
					(size 0.7 0.7)
					(thickness 0.15)
				)
				(justify left bottom mirror)
			)
		)
		(pad "1" smd roundrect
			(at -0.48 0 180)
			(size 0.59 0.64)
			(layers "B.Cu" "B.Mask" "B.Paste")
			(roundrect_rratio 0.25)
			(net 343 "/USB/EN_FTDI")
			(pintype "passive")
		)
		(pad "2" smd roundrect
			(at 0.48 0 180)
			(size 0.59 0.64)
			(layers "B.Cu" "B.Mask" "B.Paste")
			(roundrect_rratio 0.25)
			(net 26 "/USB/USBD_VBUS")
			(pintype "passive")
		)
	)
	(footprint "antmicro-footprints:FB_0603_1608Metric"
		(layer "B.Cu")
		(at 59.267962 116.4665 180)
		(property "Reference" "FB401"
			(at -1.7 -1.44 0)
			(layer "B.SilkS")
			(effects
				(font
					(size 0.7 0.7)
					(thickness 0.15)
				)
				(justify left bottom mirror)
			)
		)
		(property "Value" "FB_220Z_2.2A_TDK-MPZ_0603"
			(at 0 -1.5 0)
			(layer "B.Fab")
			(effects
				(font
					(size 0.7 0.7)
					(thickness 0.15)
				)
				(justify left bottom mirror)
			)
		)
		(property "Datasheet" "https://product.tdk.com/info/en/catalog/datasheets/beads_commercial_power_mpz1608_en.pdf"
			(at 0 0 180)
			(layer "B.Fab")
			(hide yes)
			(effects
				(font
					(size 1.27 1.27)
					(thickness 0.15)
				)
			)
		)
		(property "MPN" "MPZ1608S221ATA00"
			(at 0 0 180)
			(unlocked yes)
			(layer "B.Fab")
			(hide yes)
			(effects
				(font
					(size 1 1)
					(thickness 0.15)
				)
				(justify mirror)
			)
		)
		(property "Manufacturer" "TDK"
			(at 0 0 180)
			(unlocked yes)
			(layer "B.Fab")
			(hide yes)
			(effects
				(font
					(size 1 1)
					(thickness 0.15)
				)
				(justify mirror)
			)
		)
		(property "Author" "Antmicro"
			(at 0 0 180)
			(unlocked yes)
			(layer "B.Fab")
			(hide yes)
			(effects
				(font
					(size 1 1)
					(thickness 0.15)
				)
				(justify mirror)
			)
		)
		(property "License" "Apache-2.0"
			(at 0 0 180)
			(unlocked yes)
			(layer "B.Fab")
			(hide yes)
			(effects
				(font
					(size 1 1)
					(thickness 0.15)
				)
				(justify mirror)
			)
		)
		(property "Val" "220Z/2.2A"
			(at 0 0 180)
			(unlocked yes)
			(layer "B.Fab")
			(hide yes)
			(effects
				(font
					(size 1 1)
					(thickness 0.15)
				)
				(justify mirror)
			)
		)
		(property "Current" ""
			(at 0 0 180)
			(unlocked yes)
			(layer "B.Fab")
			(hide yes)
			(effects
				(font
					(size 1 1)
					(thickness 0.15)
				)
				(justify mirror)
			)
		)
		(sheetname "/Ethernet/")
		(sheetfile "ethernet.kicad_sch")
		(attr smd)
		(fp_line
			(start -0.15 0.4)
			(end 0.15 0.4)
			(stroke
				(width 0.15)
				(type solid)
			)
			(layer "B.SilkS")
		)
		(fp_line
			(start -0.15 -0.4)
			(end 0.15 -0.4)
			(stroke
				(width 0.15)
				(type solid)
			)
			(layer "B.SilkS")
		)
		(fp_rect
			(start -1.25 0.65)
			(end 1.25 -0.65)
			(stroke
				(width 0.05)
				(type solid)
			)
			(fill no)
			(layer "B.CrtYd")
		)
		(fp_line
			(start 0.8 0.408)
			(end 0.8 -0.406)
			(stroke
				(width 0.15)
				(type solid)
			)
			(layer "B.Fab")
		)
		(fp_line
			(start 0.8 0.408)
			(end -0.803 0.408)
			(stroke
				(width 0.15)
				(type solid)
			)
			(layer "B.Fab")
		)
		(fp_line
			(start 0.8 -0.406)
			(end -0.803 -0.406)
			(stroke
				(width 0.15)
				(type solid)
			)
			(layer "B.Fab")
		)
		(fp_line
			(start -0.803 -0.406)
			(end -0.803 0.408)
			(stroke
				(width 0.15)
				(type solid)
			)
			(layer "B.Fab")
		)
		(fp_text user "Author: Antmicro"
			(at -1.653 -3.162 0)
			(layer "B.Fab")
			(effects
				(font
					(size 0.7 0.7)
					(thickness 0.15)
				)
				(justify left bottom mirror)
			)
		)
		(fp_text user "License: Apache-2.0"
			(at -1.653 -5.9 0)
			(layer "B.Fab")
			(effects
				(font
					(size 0.7 0.7)
					(thickness 0.15)
				)
				(justify left bottom mirror)
			)
		)
		(fp_text user "${REFERENCE}"
			(at -1.653 -4.6 0)
			(layer "B.Fab")
			(effects
				(font
					(size 0.7 0.7)
					(thickness 0.15)
				)
				(justify left bottom mirror)
			)
		)
		(pad "1" smd roundrect
			(at -0.7 0 180)
			(size 0.8 1)
			(layers "B.Cu" "B.Mask" "B.Paste")
			(roundrect_rratio 0.2)
			(net 117 "Net-(D401-Pad2)")
			(pintype "passive")
		)
		(pad "2" smd roundrect
			(at 0.7 0 180)
			(size 0.8 1)
			(layers "B.Cu" "B.Mask" "B.Paste")
			(roundrect_rratio 0.2)
			(net 33 "/Ethernet/VDD")
			(pintype "passive")
		)
	)
	(footprint "antmicro-footprints:R_0402_1005Metric"
		(layer "B.Cu")
		(at 118.892962 120.0415 90)
		(descr "Resistor SMD 0402")
		(tags "resistor SMD 0402")
		(property "Reference" "R503"
			(at -2.895 -0.565 90)
			(layer "B.SilkS")
			(effects
				(font
					(size 0.7 0.7)
					(thickness 0.15)
				)
				(justify right bottom mirror)
			)
		)
		(property "Value" "R_10k_0402"
			(at -1.011843 -1.772047 90)
			(layer "B.Fab")
			(effects
				(font
					(size 0.7 0.7)
					(thickness 0.15)
				)
				(justify right bottom mirror)
			)
		)
		(property "Datasheet" "https://www.bourns.com/docs/product-datasheets/cr.pdf"
			(at 0 0 90)
			(layer "B.Fab")
			(hide yes)
			(effects
				(font
					(size 1.27 1.27)
					(thickness 0.15)
				)
			)
		)
		(property "Manufacturer" "Bourns"
			(at 0 0 90)
			(unlocked yes)
			(layer "B.Fab")
			(hide yes)
			(effects
				(font
					(size 1 1)
					(thickness 0.15)
				)
				(justify mirror)
			)
		)
		(property "MPN" "CR0402-FX-1002GLF"
			(at 0 0 90)
			(unlocked yes)
			(layer "B.Fab")
			(hide yes)
			(effects
				(font
					(size 1 1)
					(thickness 0.15)
				)
				(justify mirror)
			)
		)
		(property "Val" "10k"
			(at 0 0 90)
			(unlocked yes)
			(layer "B.Fab")
			(hide yes)
			(effects
				(font
					(size 1 1)
					(thickness 0.15)
				)
				(justify mirror)
			)
		)
		(property "License" "Apache-2.0"
			(at 0 0 90)
			(unlocked yes)
			(layer "B.Fab")
			(hide yes)
			(effects
				(font
					(size 1 1)
					(thickness 0.15)
				)
				(justify mirror)
			)
		)
		(property "Author" "Antmicro"
			(at 0 0 90)
			(unlocked yes)
			(layer "B.Fab")
			(hide yes)
			(effects
				(font
					(size 1 1)
					(thickness 0.15)
				)
				(justify mirror)
			)
		)
		(property "Tolerance" "1%"
			(at 0 0 90)
			(unlocked yes)
			(layer "B.Fab")
			(hide yes)
			(effects
				(font
					(size 1 1)
					(thickness 0.15)
				)
				(justify mirror)
			)
		)
		(sheetname "/NVMe & microSD/")
		(sheetfile "nvme-micro-sd.kicad_sch")
		(attr smd)
		(fp_rect
			(start -0.925 0.47)
			(end 0.925 -0.47)
			(stroke
				(width 0.05)
				(type default)
			)
			(fill no)
			(layer "B.CrtYd")
		)
		(fp_rect
			(start -0.5 0.25)
			(end 0.5 -0.25)
			(stroke
				(width 0.15)
				(type solid)
			)
			(fill no)
			(layer "B.Fab")
		)
		(fp_text user "License: Apache-2.0"
			(at -0.95 -5.169 270)
			(layer "B.Fab")
			(effects
				(font
					(size 0.7 0.7)
					(thickness 0.15)
				)
				(justify left bottom mirror)
			)
		)
		(fp_text user "${REFERENCE}"
			(at -0.95 -3.168 270)
			(layer "B.Fab")
			(effects
				(font
					(size 0.7 0.7)
					(thickness 0.15)
				)
				(justify left bottom mirror)
			)
		)
		(fp_text user "Author: Antmicro"
			(at -0.95 -4.169 270)
			(layer "B.Fab")
			(effects
				(font
					(size 0.7 0.7)
					(thickness 0.15)
				)
				(justify left bottom mirror)
			)
		)
		(pad "1" smd roundrect
			(at -0.48 0 90)
			(size 0.59 0.64)
			(layers "B.Cu" "B.Mask" "B.Paste")
			(roundrect_rratio 0.25)
			(net 182 "Net-(J501-~{PEWAKE})")
			(pintype "passive")
		)
		(pad "2" smd roundrect
			(at 0.48 0 90)
			(size 0.59 0.64)
			(layers "B.Cu" "B.Mask" "B.Paste")
			(roundrect_rratio 0.25)
			(net 65 "3V3_SSD")
			(pintype "passive")
		)
	)
)
